(kicad_pcb
	(version 20260206)
	(generator "pcbnew")
	(generator_version "10.0")
	(general
		(thickness 1.6)
		(legacy_teardrops no)
	)
	(paper "A4")
	(title_block
		(title "04192023_DAF0TMB3IC0_F0TG_MB_C_brd_V02_OCP.brd")
		(comment 1 "Grand Teton / footprints 6482-6487 of 8354")
	)
	(layers
		(0 "F.Cu" signal "TOP")
		(4 "In1.Cu" signal "GND")
		(6 "In2.Cu" signal "IN1")
		(8 "In3.Cu" signal "GND1")
		(10 "In4.Cu" signal "IN2")
		(12 "In5.Cu" signal "GND2")
		(14 "In6.Cu" signal "IN3")
		(16 "In7.Cu" signal "GND3")
		(18 "In8.Cu" signal "VCC")
		(20 "In9.Cu" signal "VCC1")
		(22 "In10.Cu" signal "GND4")
		(24 "In11.Cu" signal "IN4")
		(26 "In12.Cu" signal "GND5")
		(28 "In13.Cu" signal "IN5")
		(30 "In14.Cu" signal "GND6")
		(32 "In15.Cu" signal "IN6")
		(34 "In16.Cu" signal "GND7")
		(2 "B.Cu" signal "BOTTOM")
		(9 "F.Adhes" user "F.Adhesive")
		(11 "B.Adhes" user "B.Adhesive")
		(13 "F.Paste" user "Package Geometry/Pastemask Top")
		(15 "B.Paste" user "Package Geometry/Pastemask Bottom")
		(5 "F.SilkS" user "Ref Des/Silkscreen Top")
		(7 "B.SilkS" user "Ref Des/Silkscreen Bottom")
		(1 "F.Mask" user "Board Geometry/Soldermask Top")
		(3 "B.Mask" user "Board Geometry/Soldermask Bottom")
		(17 "Dwgs.User" user "User.Drawings")
		(19 "Cmts.User" user "User.Comments")
		(21 "Eco1.User" user "User.Eco1")
		(23 "Eco2.User" user "User.Eco2")
		(25 "Edge.Cuts" user "Board Geometry/Outline")
		(27 "Margin" user)
		(31 "F.CrtYd" user "Package Geometry/Place Bound Top")
		(29 "B.CrtYd" user "Package Geometry/Place Bound Bottom")
		(35 "F.Fab" user "Ref Des/Assembly Top")
		(33 "B.Fab" user "Ref Des/Assembly Bottom")
	)
	(footprint ""
		(layer "B.Cu")
		(at 71.657464 -408.517344 90)
		(property "Reference" "C6675"
			(at 0 0 90)
			(layer "B.SilkS")
			(hide yes)
			(effects
				(font
					(size 1.27 1.27)
				)
				(justify mirror)
			)
		)
		(property "Value" ""
			(at 0 0 90)
			(layer "B.Fab")
			(effects
				(font
					(size 1.27 1.27)
				)
				(justify mirror)
			)
		)
		(duplicate_pad_numbers_are_jumpers no)
		(fp_line
			(start 0.299974 -0.150114)
			(end -0.299974 -0.150114)
			(stroke
				(width 0.1)
				(type default)
			)
			(layer "B.Fab")
		)
		(fp_line
			(start -0.299974 -0.150114)
			(end -0.299974 0.150114)
			(stroke
				(width 0.1)
				(type default)
			)
			(layer "B.Fab")
		)
		(fp_line
			(start 0.299974 0.150114)
			(end 0.299974 -0.150114)
			(stroke
				(width 0.1)
				(type default)
			)
			(layer "B.Fab")
		)
		(fp_line
			(start -0.299974 0.150114)
			(end 0.299974 0.150114)
			(stroke
				(width 0.1)
				(type default)
			)
			(layer "B.Fab")
		)
		(pad "1" smd rect
			(at 0.2667 0 270)
			(size 0.3048 0.381)
			(layers "B.Cu" "B.Mask" "B.Paste")
			(net "P5E_CPU1_P1_TX_BUF_C_DP<7>")
		)
		(pad "2" smd rect
			(at -0.2667 0 270)
			(size 0.3048 0.381)
			(layers "B.Cu" "B.Mask" "B.Paste")
			(net "P5E_CPU1_P1_TX_BUF_DP<7>")
		)
	)
	(footprint ""
		(layer "B.Cu")
		(at 372.916958 -248.47931)
		(property "Reference" "C2181"
			(at 0 0 0)
			(layer "B.SilkS")
			(hide yes)
			(effects
				(font
					(size 1.27 1.27)
				)
				(justify mirror)
			)
		)
		(property "Value" ""
			(at 0 0 0)
			(layer "B.Fab")
			(effects
				(font
					(size 1.27 1.27)
				)
				(justify mirror)
			)
		)
		(duplicate_pad_numbers_are_jumpers no)
		(fp_line
			(start -0.7874 -0.4064)
			(end -0.7874 0.4064)
			(stroke
				(width 0.1524)
				(type default)
			)
			(layer "B.SilkS")
		)
		(fp_line
			(start -0.7874 0.4064)
			(end 0.7874 0.4064)
			(stroke
				(width 0.1524)
				(type default)
			)
			(layer "B.SilkS")
		)
		(fp_line
			(start 0.7874 -0.4064)
			(end -0.7874 -0.4064)
			(stroke
				(width 0.1524)
				(type default)
			)
			(layer "B.SilkS")
		)
		(fp_line
			(start 0.7874 0.4064)
			(end 0.7874 -0.4064)
			(stroke
				(width 0.1524)
				(type default)
			)
			(layer "B.SilkS")
		)
		(fp_line
			(start -0.67945 -0.3048)
			(end -0.67945 0.3048)
			(stroke
				(width 0.1)
				(type default)
			)
			(layer "B.Fab")
		)
		(fp_line
			(start -0.67945 0.3048)
			(end -0.120396 0.3048)
			(stroke
				(width 0.1)
				(type default)
			)
			(layer "B.Fab")
		)
		(fp_line
			(start -0.12065 -0.3048)
			(end -0.67945 -0.3048)
			(stroke
				(width 0.1)
				(type default)
			)
			(layer "B.Fab")
		)
		(fp_line
			(start -0.12065 -0.2794)
			(end -0.12065 -0.3048)
			(stroke
				(width 0.1)
				(type default)
			)
			(layer "B.Fab")
		)
		(fp_line
			(start -0.120396 0.2794)
			(end 0.12065 0.2794)
			(stroke
				(width 0.1)
				(type default)
			)
			(layer "B.Fab")
		)
		(fp_line
			(start -0.120396 0.3048)
			(end -0.120396 0.2794)
			(stroke
				(width 0.1)
				(type default)
			)
			(layer "B.Fab")
		)
		(fp_line
			(start 0.12065 -0.305054)
			(end 0.12065 -0.2794)
			(stroke
				(width 0.1)
				(type default)
			)
			(layer "B.Fab")
		)
		(fp_line
			(start 0.12065 -0.2794)
			(end -0.12065 -0.2794)
			(stroke
				(width 0.1)
				(type default)
			)
			(layer "B.Fab")
		)
		(fp_line
			(start 0.12065 0.2794)
			(end 0.12065 0.3048)
			(stroke
				(width 0.1)
				(type default)
			)
			(layer "B.Fab")
		)
		(fp_line
			(start 0.12065 0.3048)
			(end 0.67945 0.3048)
			(stroke
				(width 0.1)
				(type default)
			)
			(layer "B.Fab")
		)
		(fp_line
			(start 0.67945 -0.305054)
			(end 0.12065 -0.305054)
			(stroke
				(width 0.1)
				(type default)
			)
			(layer "B.Fab")
		)
		(fp_line
			(start 0.67945 0.3048)
			(end 0.67945 -0.305054)
			(stroke
				(width 0.1)
				(type default)
			)
			(layer "B.Fab")
		)
		(pad "1" smd circle
			(at 0.40005 0 180)
			(size 0 0)
			(layers "B.Cu" "B.Mask" "B.Paste")
			(net "PVDDCR_CPU0_P0")
		)
		(pad "2" smd circle
			(at -0.40005 0 180)
			(size 0 0)
			(layers "B.Cu" "B.Mask" "B.Paste")
			(net "GND")
		)
	)
	(footprint ""
		(layer "B.Cu")
		(at 163.815268 -415.75101)
		(property "Reference" "R4125"
			(at 0 0 0)
			(layer "B.SilkS")
			(hide yes)
			(effects
				(font
					(size 1.27 1.27)
				)
				(justify mirror)
			)
		)
		(property "Value" ""
			(at 0 0 0)
			(layer "B.Fab")
			(effects
				(font
					(size 1.27 1.27)
				)
				(justify mirror)
			)
		)
		(duplicate_pad_numbers_are_jumpers no)
		(fp_line
			(start -0.7874 -0.4064)
			(end -0.7874 0.4064)
			(stroke
				(width 0.1524)
				(type default)
			)
			(layer "B.SilkS")
		)
		(fp_line
			(start -0.7874 0.4064)
			(end 0.7874 0.4064)
			(stroke
				(width 0.1524)
				(type default)
			)
			(layer "B.SilkS")
		)
		(fp_line
			(start 0.7874 -0.4064)
			(end -0.7874 -0.4064)
			(stroke
				(width 0.1524)
				(type default)
			)
			(layer "B.SilkS")
		)
		(fp_line
			(start 0.7874 0.4064)
			(end 0.7874 -0.4064)
			(stroke
				(width 0.1524)
				(type default)
			)
			(layer "B.SilkS")
		)
		(fp_line
			(start -0.67945 -0.3048)
			(end -0.67945 0.3048)
			(stroke
				(width 0.1)
				(type default)
			)
			(layer "B.Fab")
		)
		(fp_line
			(start -0.67945 0.3048)
			(end -0.120396 0.3048)
			(stroke
				(width 0.1)
				(type default)
			)
			(layer "B.Fab")
		)
		(fp_line
			(start -0.12065 -0.3048)
			(end -0.67945 -0.3048)
			(stroke
				(width 0.1)
				(type default)
			)
			(layer "B.Fab")
		)
		(fp_line
			(start -0.12065 -0.2794)
			(end -0.12065 -0.3048)
			(stroke
				(width 0.1)
				(type default)
			)
			(layer "B.Fab")
		)
		(fp_line
			(start -0.120396 0.2794)
			(end 0.12065 0.2794)
			(stroke
				(width 0.1)
				(type default)
			)
			(layer "B.Fab")
		)
		(fp_line
			(start -0.120396 0.3048)
			(end -0.120396 0.2794)
			(stroke
				(width 0.1)
				(type default)
			)
			(layer "B.Fab")
		)
		(fp_line
			(start 0.12065 -0.305054)
			(end 0.12065 -0.2794)
			(stroke
				(width 0.1)
				(type default)
			)
			(layer "B.Fab")
		)
		(fp_line
			(start 0.12065 -0.2794)
			(end -0.12065 -0.2794)
			(stroke
				(width 0.1)
				(type default)
			)
			(layer "B.Fab")
		)
		(fp_line
			(start 0.12065 0.2794)
			(end 0.12065 0.3048)
			(stroke
				(width 0.1)
				(type default)
			)
			(layer "B.Fab")
		)
		(fp_line
			(start 0.12065 0.3048)
			(end 0.67945 0.3048)
			(stroke
				(width 0.1)
				(type default)
			)
			(layer "B.Fab")
		)
		(fp_line
			(start 0.67945 -0.305054)
			(end 0.12065 -0.305054)
			(stroke
				(width 0.1)
				(type default)
			)
			(layer "B.Fab")
		)
		(fp_line
			(start 0.67945 0.3048)
			(end 0.67945 -0.305054)
			(stroke
				(width 0.1)
				(type default)
			)
			(layer "B.Fab")
		)
		(pad "1" smd circle
			(at 0.40005 0 180)
			(size 0 0)
			(layers "B.Cu" "B.Mask" "B.Paste")
			(net "P3V3_AUX")
		)
		(pad "2" smd circle
			(at -0.40005 0 180)
			(size 0 0)
			(layers "B.Cu" "B.Mask" "B.Paste")
			(net "GPU_3V3IO_RSVD0_FFU_N")
		)
	)
	(footprint ""
		(layer "B.Cu")
		(at 90.209878 -141.83741)
		(property "Reference" "C248"
			(at 0 0 0)
			(layer "B.SilkS")
			(hide yes)
			(effects
				(font
					(size 1.27 1.27)
				)
				(justify mirror)
			)
		)
		(property "Value" ""
			(at 0 0 0)
			(layer "B.Fab")
			(effects
				(font
					(size 1.27 1.27)
				)
				(justify mirror)
			)
		)
		(duplicate_pad_numbers_are_jumpers no)
		(fp_line
			(start -0.7874 -0.4064)
			(end -0.7874 0.4064)
			(stroke
				(width 0.1524)
				(type default)
			)
			(layer "B.SilkS")
		)
		(fp_line
			(start -0.7874 0.4064)
			(end 0.7874 0.4064)
			(stroke
				(width 0.1524)
				(type default)
			)
			(layer "B.SilkS")
		)
		(fp_line
			(start 0.7874 -0.4064)
			(end -0.7874 -0.4064)
			(stroke
				(width 0.1524)
				(type default)
			)
			(layer "B.SilkS")
		)
		(fp_line
			(start 0.7874 0.4064)
			(end 0.7874 -0.4064)
			(stroke
				(width 0.1524)
				(type default)
			)
			(layer "B.SilkS")
		)
		(fp_line
			(start -0.67945 -0.3048)
			(end -0.67945 0.3048)
			(stroke
				(width 0.1)
				(type default)
			)
			(layer "B.Fab")
		)
		(fp_line
			(start -0.67945 0.3048)
			(end -0.120396 0.3048)
			(stroke
				(width 0.1)
				(type default)
			)
			(layer "B.Fab")
		)
		(fp_line
			(start -0.12065 -0.3048)
			(end -0.67945 -0.3048)
			(stroke
				(width 0.1)
				(type default)
			)
			(layer "B.Fab")
		)
		(fp_line
			(start -0.12065 -0.2794)
			(end -0.12065 -0.3048)
			(stroke
				(width 0.1)
				(type default)
			)
			(layer "B.Fab")
		)
		(fp_line
			(start -0.120396 0.2794)
			(end 0.12065 0.2794)
			(stroke
				(width 0.1)
				(type default)
			)
			(layer "B.Fab")
		)
		(fp_line
			(start -0.120396 0.3048)
			(end -0.120396 0.2794)
			(stroke
				(width 0.1)
				(type default)
			)
			(layer "B.Fab")
		)
		(fp_line
			(start 0.12065 -0.305054)
			(end 0.12065 -0.2794)
			(stroke
				(width 0.1)
				(type default)
			)
			(layer "B.Fab")
		)
		(fp_line
			(start 0.12065 -0.2794)
			(end -0.12065 -0.2794)
			(stroke
				(width 0.1)
				(type default)
			)
			(layer "B.Fab")
		)
		(fp_line
			(start 0.12065 0.2794)
			(end 0.12065 0.3048)
			(stroke
				(width 0.1)
				(type default)
			)
			(layer "B.Fab")
		)
		(fp_line
			(start 0.12065 0.3048)
			(end 0.67945 0.3048)
			(stroke
				(width 0.1)
				(type default)
			)
			(layer "B.Fab")
		)
		(fp_line
			(start 0.67945 -0.305054)
			(end 0.12065 -0.305054)
			(stroke
				(width 0.1)
				(type default)
			)
			(layer "B.Fab")
		)
		(fp_line
			(start 0.67945 0.3048)
			(end 0.67945 -0.305054)
			(stroke
				(width 0.1)
				(type default)
			)
			(layer "B.Fab")
		)
		(pad "1" smd circle
			(at 0.40005 0 180)
			(size 0 0)
			(layers "B.Cu" "B.Mask" "B.Paste")
			(net "PWRGD_PVDDCR_CPU0_P1_R")
		)
		(pad "2" smd circle
			(at -0.40005 0 180)
			(size 0 0)
			(layers "B.Cu" "B.Mask" "B.Paste")
			(net "GND")
		)
	)
	(footprint ""
		(layer "B.Cu")
		(at 5.985002 -403.945852 180)
		(property "Reference" ""
			(at 0 0 0)
			(layer "B.SilkS")
			(hide yes)
			(effects
				(font
					(size 1.27 1.27)
				)
				(justify mirror)
			)
		)
		(property "Value" ""
			(at 0 0 0)
			(layer "B.Fab")
			(effects
				(font
					(size 1.27 1.27)
				)
				(justify mirror)
			)
		)
		(duplicate_pad_numbers_are_jumpers no)
		(pad "1" smd circle
			(at 0 0)
			(size 0.9906 0.9906)
			(layers "B.Cu" "B.Mask" "B.Paste")
			(net "Net_2231")
		)
		(zone
			(layer "B.Cu")
			(hatch none 0.5)
			(connect_pads
				(clearance 0)
			)
			(min_thickness 0.25)
			(keepout
				(tracks not_allowed)
				(vias allowed)
				(pads allowed)
				(copperpour not_allowed)
				(footprints allowed)
			)
			(placement
				(enabled no)
				(sheetname "")
			)
			(fill
				(thermal_gap 0.5)
				(thermal_bridge_width 0.5)
				(island_removal_mode 0)
			)
			(polygon
				(pts
					(arc
						(start 7.610602 -403.945852)
						(mid 4.359402 -403.945852)
						(end 7.610602 -403.945852)
					)
				)
			)
		)
	)
	(footprint ""
		(layer "B.Cu")
		(at 354.812854 -420.626032 90)
		(property "Reference" "R2841"
			(at 0 0 90)
			(layer "B.SilkS")
			(hide yes)
			(effects
				(font
					(size 1.27 1.27)
				)
				(justify mirror)
			)
		)
		(property "Value" ""
			(at 0 0 90)
			(layer "B.Fab")
			(effects
				(font
					(size 1.27 1.27)
				)
				(justify mirror)
			)
		)
		(duplicate_pad_numbers_are_jumpers no)
		(fp_line
			(start 0.7874 -0.4064)
			(end -0.7874 -0.4064)
			(stroke
				(width 0.1524)
				(type default)
			)
			(layer "B.SilkS")
		)
		(fp_line
			(start -0.7874 -0.4064)
			(end -0.7874 0.4064)
			(stroke
				(width 0.1524)
				(type default)
			)
			(layer "B.SilkS")
		)
		(fp_line
			(start 0.7874 0.4064)
			(end 0.7874 -0.4064)
			(stroke
				(width 0.1524)
				(type default)
			)
			(layer "B.SilkS")
		)
		(fp_line
			(start -0.7874 0.4064)
			(end 0.7874 0.4064)
			(stroke
				(width 0.1524)
				(type default)
			)
			(layer "B.SilkS")
		)
		(fp_line
			(start 0.67945 -0.305054)
			(end 0.12065 -0.305054)
			(stroke
				(width 0.1)
				(type default)
			)
			(layer "B.Fab")
		)
		(fp_line
			(start 0.12065 -0.305054)
			(end 0.12065 -0.2794)
			(stroke
				(width 0.1)
				(type default)
			)
			(layer "B.Fab")
		)
		(fp_line
			(start -0.12065 -0.3048)
			(end -0.67945 -0.3048)
			(stroke
				(width 0.1)
				(type default)
			)
			(layer "B.Fab")
		)
		(fp_line
			(start -0.67945 -0.3048)
			(end -0.67945 0.3048)
			(stroke
				(width 0.1)
				(type default)
			)
			(layer "B.Fab")
		)
		(fp_line
			(start 0.12065 -0.2794)
			(end -0.12065 -0.2794)
			(stroke
				(width 0.1)
				(type default)
			)
			(layer "B.Fab")
		)
		(fp_line
			(start -0.12065 -0.2794)
			(end -0.12065 -0.3048)
			(stroke
				(width 0.1)
				(type default)
			)
			(layer "B.Fab")
		)
		(fp_line
			(start 0.12065 0.2794)
			(end 0.12065 0.3048)
			(stroke
				(width 0.1)
				(type default)
			)
			(layer "B.Fab")
		)
		(fp_line
			(start -0.120396 0.2794)
			(end 0.12065 0.2794)
			(stroke
				(width 0.1)
				(type default)
			)
			(layer "B.Fab")
		)
		(fp_line
			(start 0.67945 0.3048)
			(end 0.67945 -0.305054)
			(stroke
				(width 0.1)
				(type default)
			)
			(layer "B.Fab")
		)
		(fp_line
			(start 0.12065 0.3048)
			(end 0.67945 0.3048)
			(stroke
				(width 0.1)
				(type default)
			)
			(layer "B.Fab")
		)
		(fp_line
			(start -0.120396 0.3048)
			(end -0.120396 0.2794)
			(stroke
				(width 0.1)
				(type default)
			)
			(layer "B.Fab")
		)
		(fp_line
			(start -0.67945 0.3048)
			(end -0.120396 0.3048)
			(stroke
				(width 0.1)
				(type default)
			)
			(layer "B.Fab")
		)
		(pad "1" smd circle
			(at 0.40005 0 270)
			(size 0 0)
			(layers "B.Cu" "B.Mask" "B.Paste")
			(net "P3V3_AUX")
		)
		(pad "2" smd circle
			(at -0.40005 0 270)
			(size 0 0)
			(layers "B.Cu" "B.Mask" "B.Paste")
			(net "FM_SWB_PWRGD_N")
		)
	)
)
